# BASEBOARD_FAB2 (Tioga Pass) — schematic netlist excerpt (pin names and nets, part order shuffled) for the footprints in the layout excerpt that follows; sources: Cadence DE-HDL packaged netlist, KiCad conversion of Wiwynn_Tioga_Pass_MB.brd

R8B6  RES  1.8K 1% CHIP  pkg 0402  page 91 : A = PVPP_ABC ; B = SMB_HFI0_CPU0_LVC2_SCL
R8E40  RES  100.0K 1% EMPTY  pkg 0402  page 240 : A = P3V3_STBY ; B = VR_P3V3_STBY_EN
C7A40  CAP_A  0.1UF 16V 10% X7R  pkg 0402V  page 236 : A = VR_FET_SW_P12V_STBY_PVDDQ_DEF ; B = GND

(kicad_pcb
	(version 20260206)
	(generator "pcbnew")
	(generator_version "10.0")
	(general
		(thickness 1.6)
		(legacy_teardrops no)
	)
	(paper "A4")
	(title_block
		(title "Wiwynn_Tioga_Pass_MB.brd")
		(comment 1 "Tioga Pass / footprints 643-645 of 4770")
	)
	(layers
		(0 "F.Cu" signal "TOP")
		(4 "In1.Cu" signal "L2GND")
		(6 "In2.Cu" signal "L3")
		(8 "In3.Cu" signal "L4GND")
		(10 "In4.Cu" signal "L5")
		(12 "In5.Cu" signal "L6GND")
		(14 "In6.Cu" signal "L7VCC")
		(16 "In7.Cu" signal "L8VCC")
		(18 "In8.Cu" signal "L9GND")
		(20 "In9.Cu" signal "L10")
		(22 "In10.Cu" signal "L11GND")
		(24 "In11.Cu" signal "L12")
		(26 "In12.Cu" signal "L13GND")
		(2 "B.Cu" signal "BOTTOM")
		(9 "F.Adhes" user "F.Adhesive")
		(11 "B.Adhes" user "B.Adhesive")
		(13 "F.Paste" user "Package Geometry/Pastemask Top")
		(15 "B.Paste" user "Package Geometry/Pastemask Bottom")
		(5 "F.SilkS" user "Ref Des/Silkscreen Top")
		(7 "B.SilkS" user "Ref Des/Silkscreen Bottom")
		(1 "F.Mask" user "Board Geometry/Soldermask Top")
		(3 "B.Mask" user "Board Geometry/Soldermask Bottom")
		(17 "Dwgs.User" user "User.Drawings")
		(19 "Cmts.User" user "User.Comments")
		(21 "Eco1.User" user "User.Eco1")
		(23 "Eco2.User" user "User.Eco2")
		(25 "Edge.Cuts" user "Board Geometry/Outline")
		(27 "Margin" user)
		(31 "F.CrtYd" user "Package Geometry/Place Bound Top")
		(29 "B.CrtYd" user "Package Geometry/Place Bound Bottom")
		(35 "F.Fab" user "Ref Des/Assembly Top")
		(33 "B.Fab" user "Ref Des/Assembly Bottom")
	)
	(footprint ""
		(layer "F.Cu")
		(at 426.5295 -130.556 -90)
		(property "Reference" "R8B6"
			(at 0 0 270)
			(layer "F.SilkS")
			(hide yes)
			(effects
				(font
					(size 1.27 1.27)
				)
			)
		)
		(property "Value" ""
			(at 0 0 270)
			(layer "F.Fab")
			(effects
				(font
					(size 1.27 1.27)
				)
			)
		)
		(duplicate_pad_numbers_are_jumpers no)
		(fp_poly
			(pts
				(xy -0.2794 -0.1016) (xy 0.2794 -0.1016) (xy 0.2794 0.9906) (xy -0.2794 0.9906)
			)
			(stroke
				(width 0)
				(type default)
			)
			(fill no)
			(layer "F.CrtYd")
		)
		(fp_line
			(start -0.2794 0.9906)
			(end 0.2794 0.9906)
			(stroke
				(width 0.1)
				(type default)
			)
			(layer "F.Fab")
		)
		(fp_line
			(start 0.2794 0.9906)
			(end 0.2794 -0.1016)
			(stroke
				(width 0.1)
				(type default)
			)
			(layer "F.Fab")
		)
		(fp_line
			(start -0.2794 -0.1016)
			(end -0.2794 0.9906)
			(stroke
				(width 0.1)
				(type default)
			)
			(layer "F.Fab")
		)
		(fp_line
			(start 0.2794 -0.1016)
			(end -0.2794 -0.1016)
			(stroke
				(width 0.1)
				(type default)
			)
			(layer "F.Fab")
		)
		(pad "1" smd rect
			(at 0 0 270)
			(size 0.508 0.508)
			(layers "F.Cu" "F.Mask" "F.Paste")
			(net "PVPP_ABC")
		)
		(pad "2" smd rect
			(at 0 0.889 270)
			(size 0.508 0.508)
			(layers "F.Cu" "F.Mask" "F.Paste")
			(net "SMB_HFI0_CPU0_LVC2_SCL")
		)
		(zone
			(layer "F.Cu")
			(hatch none 0.5)
			(connect_pads
				(clearance 0)
			)
			(min_thickness 0.25)
			(keepout
				(tracks not_allowed)
				(vias allowed)
				(pads allowed)
				(copperpour not_allowed)
				(footprints allowed)
			)
			(placement
				(enabled no)
				(sheetname "")
			)
			(fill
				(thermal_gap 0.5)
				(thermal_bridge_width 0.5)
				(island_removal_mode 0)
			)
			(polygon
				(pts
					(xy 425.8945 -130.81) (xy 425.8945 -130.302) (xy 426.2755 -130.302) (xy 426.2755 -130.81)
				)
			)
		)
		(zone
			(layer "F.Cu")
			(hatch none 0.5)
			(connect_pads
				(clearance 0)
			)
			(min_thickness 0.25)
			(keepout
				(tracks allowed)
				(vias not_allowed)
				(pads allowed)
				(copperpour not_allowed)
				(footprints allowed)
			)
			(placement
				(enabled no)
				(sheetname "")
			)
			(fill
				(thermal_gap 0.5)
				(thermal_bridge_width 0.5)
				(island_removal_mode 0)
			)
			(polygon
				(pts
					(xy 426.2755 -130.81) (xy 426.2755 -130.302) (xy 425.8945 -130.302) (xy 425.8945 -130.81)
				)
			)
		)
	)
	(footprint ""
		(layer "F.Cu")
		(at 464.7057 -24.0157 90)
		(property "Reference" "R8E40"
			(at 0 0 90)
			(layer "F.SilkS")
			(hide yes)
			(effects
				(font
					(size 1.27 1.27)
				)
			)
		)
		(property "Value" ""
			(at 0 0 90)
			(layer "F.Fab")
			(effects
				(font
					(size 1.27 1.27)
				)
			)
		)
		(duplicate_pad_numbers_are_jumpers no)
		(fp_poly
			(pts
				(xy -0.2794 -0.1016) (xy 0.2794 -0.1016) (xy 0.2794 0.9906) (xy -0.2794 0.9906)
			)
			(stroke
				(width 0)
				(type default)
			)
			(fill no)
			(layer "F.CrtYd")
		)
		(fp_line
			(start 0.2794 -0.1016)
			(end -0.2794 -0.1016)
			(stroke
				(width 0.1)
				(type default)
			)
			(layer "F.Fab")
		)
		(fp_line
			(start -0.2794 -0.1016)
			(end -0.2794 0.9906)
			(stroke
				(width 0.1)
				(type default)
			)
			(layer "F.Fab")
		)
		(fp_line
			(start 0.2794 0.9906)
			(end 0.2794 -0.1016)
			(stroke
				(width 0.1)
				(type default)
			)
			(layer "F.Fab")
		)
		(fp_line
			(start -0.2794 0.9906)
			(end 0.2794 0.9906)
			(stroke
				(width 0.1)
				(type default)
			)
			(layer "F.Fab")
		)
		(pad "1" smd rect
			(at 0 0 90)
			(size 0.508 0.508)
			(layers "F.Cu" "F.Mask" "F.Paste")
			(net "P3V3_STBY")
		)
		(pad "2" smd rect
			(at 0 0.889 90)
			(size 0.508 0.508)
			(layers "F.Cu" "F.Mask" "F.Paste")
			(net "VR_P3V3_STBY_EN")
		)
		(zone
			(layer "F.Cu")
			(hatch none 0.5)
			(connect_pads
				(clearance 0)
			)
			(min_thickness 0.25)
			(keepout
				(tracks allowed)
				(vias not_allowed)
				(pads allowed)
				(copperpour not_allowed)
				(footprints allowed)
			)
			(placement
				(enabled no)
				(sheetname "")
			)
			(fill
				(thermal_gap 0.5)
				(thermal_bridge_width 0.5)
				(island_removal_mode 0)
			)
			(polygon
				(pts
					(xy 464.9597 -23.7617) (xy 464.9597 -24.2697) (xy 465.3407 -24.2697) (xy 465.3407 -23.7617)
				)
			)
		)
		(zone
			(layer "F.Cu")
			(hatch none 0.5)
			(connect_pads
				(clearance 0)
			)
			(min_thickness 0.25)
			(keepout
				(tracks not_allowed)
				(vias allowed)
				(pads allowed)
				(copperpour not_allowed)
				(footprints allowed)
			)
			(placement
				(enabled no)
				(sheetname "")
			)
			(fill
				(thermal_gap 0.5)
				(thermal_bridge_width 0.5)
				(island_removal_mode 0)
			)
			(polygon
				(pts
					(xy 465.3407 -23.7617) (xy 465.3407 -24.2697) (xy 464.9597 -24.2697) (xy 464.9597 -23.7617)
				)
			)
		)
	)
	(footprint ""
		(layer "F.Cu")
		(at 388.8359 -154.2161)
		(property "Reference" "C7A40"
			(at 0 0 0)
			(layer "F.SilkS")
			(hide yes)
			(effects
				(font
					(size 1.27 1.27)
				)
			)
		)
		(property "Value" ""
			(at 0 0 0)
			(layer "F.Fab")
			(effects
				(font
					(size 1.27 1.27)
				)
			)
		)
		(duplicate_pad_numbers_are_jumpers no)
		(fp_poly
			(pts
				(xy 0.3048 -0.1016) (xy 0.3048 0.9906) (xy -0.3048 0.9906) (xy -0.3048 -0.1016)
			)
			(stroke
				(width 0)
				(type default)
			)
			(fill no)
			(layer "F.CrtYd")
		)
		(fp_line
			(start -0.3048 -0.1016)
			(end -0.3048 0.9906)
			(stroke
				(width 0.1)
				(type default)
			)
			(layer "F.Fab")
		)
		(fp_line
			(start -0.3048 0.9906)
			(end 0.3048 0.9906)
			(stroke
				(width 0.1)
				(type default)
			)
			(layer "F.Fab")
		)
		(fp_line
			(start 0.3048 -0.1016)
			(end -0.3048 -0.1016)
			(stroke
				(width 0.1)
				(type default)
			)
			(layer "F.Fab")
		)
		(fp_line
			(start 0.3048 0.9906)
			(end 0.3048 -0.1016)
			(stroke
				(width 0.1)
				(type default)
			)
			(layer "F.Fab")
		)
		(pad "1" smd rect
			(at 0 0)
			(size 0.508 0.508)
			(layers "F.Cu" "F.Mask" "F.Paste")
			(net "VR_FET_SW_P12V_STBY_PVDDQ_DEF")
		)
		(pad "2" smd rect
			(at 0 0.889)
			(size 0.508 0.508)
			(layers "F.Cu" "F.Mask" "F.Paste")
			(net "GND")
		)
		(zone
			(layer "F.Cu")
			(hatch none 0.5)
			(connect_pads
				(clearance 0)
			)
			(min_thickness 0.25)
			(keepout
				(tracks allowed)
				(vias not_allowed)
				(pads allowed)
				(copperpour not_allowed)
				(footprints allowed)
			)
			(placement
				(enabled no)
				(sheetname "")
			)
			(fill
				(thermal_gap 0.5)
				(thermal_bridge_width 0.5)
				(island_removal_mode 0)
			)
			(polygon
				(pts
					(xy 388.5819 -153.9621) (xy 389.0899 -153.9621) (xy 389.0899 -153.5811) (xy 388.5819 -153.5811)
				)
			)
		)
		(zone
			(layer "F.Cu")
			(hatch none 0.5)
			(connect_pads
				(clearance 0)
			)
			(min_thickness 0.25)
			(keepout
				(tracks not_allowed)
				(vias allowed)
				(pads allowed)
				(copperpour not_allowed)
				(footprints allowed)
			)
			(placement
				(enabled no)
				(sheetname "")
			)
			(fill
				(thermal_gap 0.5)
				(thermal_bridge_width 0.5)
				(island_removal_mode 0)
			)
			(polygon
				(pts
					(xy 388.5819 -153.5811) (xy 389.0899 -153.5811) (xy 389.0899 -153.9621) (xy 388.5819 -153.9621)
				)
			)
		)
	)
)
